# S9S_MB_2U (Grand Teton) — schematic netlist excerpt (pin names and nets, part order shuffled) for the footprints in the layout excerpt that follows; sources: Cadence DE-HDL packaged netlist, KiCad conversion of 03242023_DA0F0TMBIJ0_F0T_Motherboard_J_brd_V01_OCP.brd

J59  SCONN75K_APCI0155P004A  SCONN75K_APCI0155-P004A EMPTY  pkg CON_F67S2H2D2S_P0-5W7-55_LUVXB_H270  page 190
  GND1  = PCIE_M2_SSD0_PRSNT_N
  \3.3v_1\  = P3V3_M2_0
  GND2  = GND
  \3.3v_2\  = P3V3_M2_0
  PERN3  = P3E_PCH_M2_RX_DN<0>
  NC1  = NC_M2_0_NC1
  PERP3  = P3E_PCH_M2_RX_DP<0>
  NC2  = NC_M2_0_NC2
  GND3  = GND
  \das_dss#||led1#\  = LED_M2_SSD_0_ACT_N
  PETN3  = P3E_PCH_M2_TX_C_DP<0>
  \3.3v_3\  = P3V3_M2_0
  PETP3  = P3E_PCH_M2_TX_C_DN<0>
  \3.3v_4\  = P3V3_M2_0
  GND4  = GND
  \3.3v_5\  = P3V3_M2_0
  PERN2  = P3E_PCH_M2_RX_DN<1>
  \3.3v_6\  = P3V3_M2_0
  PERP2  = P3E_PCH_M2_RX_DP<1>
  NC3  = NC_M2_0_NC3
  GND5  = GND
  NC4  = NC_M2_0_NC4
  PETN2  = P3E_PCH_M2_TX_C_DP<1>
  NC5  = NC_M2_0_NC5
  PETP2  = P3E_PCH_M2_TX_C_DN<1>
  NC6  = NC_M2_0_NC6
  GND6  = GND
  NC7  = NC_M2_0_NC7
  PERN1  = P3E_PCH_M2_RX_DN<2>
  NC8  = NC_M2_0_NC8
  PERP1  = P3E_PCH_M2_RX_DP<2>
  NC9  = NC_M2_0_NC9
  GND7  = GND
  NC10  = NC_M2_0_NC10
  PETN1  = P3E_PCH_M2_TX_C_DP<2>
  NC11  = NC_M2_0_NC11
  PETP1  = P3E_PCH_M2_TX_C_DN<2>
  DEVSLP  = PD_M2_0_DEVSLP
  GND8  = GND
  NC12  = SMB_M2_P0_1V8AUX_SCL
  \pern0||sata-b+\  = P3E_PCH_M2_RX_DN<3>
  NC13  = SMB_M2_P0_1V8AUX_SDA
  \perp0||sata-b-\  = P3E_PCH_M2_RX_DP<3>
  NC14  = NC_M2_0_NC14
  GND9  = GND
  NC15  = NC_M2_0_NC15
  \petn0||sata-a-\  = P3E_PCH_M2_TX_C_DP<3>
  NC16  = NC_M2_0_NC16
  \petp0||sata-a+\  = P3E_PCH_M2_TX_C_DN<3>
  \perst#\  = RST_PCIE_PCH_DEV_0_N
  GND10  = GND
  \clkreq#\  = M2_SSD0_CLKREQ_EN_N_BUF
  REFCLKN  = CLK_100M_PE_M2_0_DN
  \pewake#\  = M2_0_PEWAKE_N
  REFCLKP  = CLK_100M_PE_M2_0_DP
  NC17  = NC_M2_0_NC17
  GND11  = GND
  NC18  = NC_M2_0_NC18
  NC19  = NC_M2_0_NC19
  SUSCLK  = NC_M2_0_SUSCLK
  PEDET  = FM_M2_SSD_0_PEDET
  \3.3v_7\  = P3V3_M2_0
  GND12  = GND
  \3.3v_8\  = P3V3_M2_0
  GND13  = GND
  \3.3v_9\  = P3V3_M2_0
  GND14  = GND
  G1  = GND
  G2  = GND

(kicad_pcb
	(version 20260206)
	(generator "pcbnew")
	(generator_version "10.0")
	(general
		(thickness 1.6)
		(legacy_teardrops no)
	)
	(paper "A4")
	(title_block
		(title "03242023_DA0F0TMBIJ0_F0T_Motherboard_J_brd_V01_OCP.brd")
		(comment 1 "Grand Teton / footprint 3483 of 6105 (J59), pads 1-44 of 71")
	)
	(layers
		(0 "F.Cu" signal "TOP")
		(4 "In1.Cu" signal "GND")
		(6 "In2.Cu" signal "IN1")
		(8 "In3.Cu" signal "GND1")
		(10 "In4.Cu" signal "IN2")
		(12 "In5.Cu" signal "GND2")
		(14 "In6.Cu" signal "IN3")
		(16 "In7.Cu" signal "GND3")
		(18 "In8.Cu" signal "VCC")
		(20 "In9.Cu" signal "VCC1")
		(22 "In10.Cu" signal "GND4")
		(24 "In11.Cu" signal "IN4")
		(26 "In12.Cu" signal "GND5")
		(28 "In13.Cu" signal "IN5")
		(30 "In14.Cu" signal "GND6")
		(32 "In15.Cu" signal "IN6")
		(34 "In16.Cu" signal "GND7")
		(2 "B.Cu" signal "BOTTOM")
		(9 "F.Adhes" user "F.Adhesive")
		(11 "B.Adhes" user "B.Adhesive")
		(13 "F.Paste" user "Package Geometry/Pastemask Top")
		(15 "B.Paste" user "Package Geometry/Pastemask Bottom")
		(5 "F.SilkS" user "Ref Des/Silkscreen Top")
		(7 "B.SilkS" user "Ref Des/Silkscreen Bottom")
		(1 "F.Mask" user "Board Geometry/Soldermask Top")
		(3 "B.Mask" user "Board Geometry/Soldermask Bottom")
		(17 "Dwgs.User" user "User.Drawings")
		(19 "Cmts.User" user "User.Comments")
		(21 "Eco1.User" user "User.Eco1")
		(23 "Eco2.User" user "User.Eco2")
		(25 "Edge.Cuts" user "Board Geometry/Outline")
		(27 "Margin" user)
		(31 "F.CrtYd" user "Package Geometry/Place Bound Top")
		(29 "B.CrtYd" user "Package Geometry/Place Bound Bottom")
		(35 "F.Fab" user "Ref Des/Assembly Top")
		(33 "B.Fab" user "Ref Des/Assembly Bottom")
	)
	(footprint ""
		(layer "F.Cu")
		(at 173.358048 -47.049944)
		(property "Reference" "J59"
			(at 5.590032 -12.227814 0)
			(unlocked yes)
			(layer "F.SilkS")
			(effects
				(font
					(size 0.7874 0.5842)
					(thickness 0.1524)
				)
				(justify left)
			)
		)
		(property "Value" ""
			(at 0 0 0)
			(layer "F.Fab")
			(effects
				(font
					(size 1.27 1.27)
				)
			)
		)
		(duplicate_pad_numbers_are_jumpers no)
		(pad "" np_thru_hole circle
			(at -1.525016 -9.99998 270)
			(size 1.1684 1.1684)
			(drill 1.1684)
			(layers "*.Cu" "*.Mask")
			(clearance 0.381)
			(thermal_gap 0.381)
		)
		(pad "" np_thru_hole circle
			(at -1.525016 9.99998 270)
			(size 1.651 1.651)
			(drill 1.651)
			(layers "*.Cu" "*.Mask")
			(clearance 0.381)
			(thermal_gap 0.381)
		)
		(pad "1" smd rect
			(at 3.750056 -9.249918 270)
			(size 0.2794 1.6002)
			(layers "F.Cu" "F.Mask" "F.Paste")
			(net "PCIE_M2_SSD0_PRSNT_N")
		)
		(pad "2" smd rect
			(at -3.800094 -8.999982 270)
			(size 0.2794 1.6002)
			(layers "F.Cu" "F.Mask" "F.Paste")
			(net "P3V3_M2_0")
		)
		(pad "3" smd rect
			(at 3.750056 -8.750046 270)
			(size 0.2794 1.6002)
			(layers "F.Cu" "F.Mask" "F.Paste")
			(net "GND")
		)
		(pad "4" smd rect
			(at -3.800094 -8.50011 270)
			(size 0.2794 1.6002)
			(layers "F.Cu" "F.Mask" "F.Paste")
			(net "P3V3_M2_0")
		)
		(pad "5" smd rect
			(at 3.750056 -8.24992 270)
			(size 0.2794 1.6002)
			(layers "F.Cu" "F.Mask" "F.Paste")
			(net "P3E_PCH_M2_RX_DN<0>")
		)
		(pad "6" smd rect
			(at -3.800094 -7.999984 270)
			(size 0.2794 1.6002)
			(layers "F.Cu" "F.Mask" "F.Paste")
			(net "NC_M2_0_NC1")
		)
		(pad "7" smd rect
			(at 3.750056 -7.750048 270)
			(size 0.2794 1.6002)
			(layers "F.Cu" "F.Mask" "F.Paste")
			(net "P3E_PCH_M2_RX_DP<0>")
		)
		(pad "8" smd rect
			(at -3.800094 -7.500112 270)
			(size 0.2794 1.6002)
			(layers "F.Cu" "F.Mask" "F.Paste")
			(net "NC_M2_0_NC2")
		)
		(pad "9" smd rect
			(at 3.750056 -7.249922 270)
			(size 0.2794 1.6002)
			(layers "F.Cu" "F.Mask" "F.Paste")
			(net "GND")
		)
		(pad "10" smd rect
			(at -3.800094 -6.999986 270)
			(size 0.2794 1.6002)
			(layers "F.Cu" "F.Mask" "F.Paste")
			(net "LED_M2_SSD_0_ACT_N")
		)
		(pad "11" smd rect
			(at 3.750056 -6.75005 270)
			(size 0.2794 1.6002)
			(layers "F.Cu" "F.Mask" "F.Paste")
			(net "P3E_PCH_M2_TX_C_DP<0>")
		)
		(pad "12" smd rect
			(at -3.800094 -6.500114 270)
			(size 0.2794 1.6002)
			(layers "F.Cu" "F.Mask" "F.Paste")
			(net "P3V3_M2_0")
		)
		(pad "13" smd rect
			(at 3.750056 -6.249924 270)
			(size 0.2794 1.6002)
			(layers "F.Cu" "F.Mask" "F.Paste")
			(net "P3E_PCH_M2_TX_C_DN<0>")
		)
		(pad "14" smd rect
			(at -3.800094 -5.999988 270)
			(size 0.2794 1.6002)
			(layers "F.Cu" "F.Mask" "F.Paste")
			(net "P3V3_M2_0")
		)
		(pad "15" smd rect
			(at 3.750056 -5.750052 270)
			(size 0.2794 1.6002)
			(layers "F.Cu" "F.Mask" "F.Paste")
			(net "GND")
		)
		(pad "16" smd rect
			(at -3.800094 -5.500116 270)
			(size 0.2794 1.6002)
			(layers "F.Cu" "F.Mask" "F.Paste")
			(net "P3V3_M2_0")
		)
		(pad "17" smd rect
			(at 3.750056 -5.249926 270)
			(size 0.2794 1.6002)
			(layers "F.Cu" "F.Mask" "F.Paste")
			(net "P3E_PCH_M2_RX_DN<1>")
		)
		(pad "18" smd rect
			(at -3.800094 -4.99999 270)
			(size 0.2794 1.6002)
			(layers "F.Cu" "F.Mask" "F.Paste")
			(net "P3V3_M2_0")
		)
		(pad "19" smd rect
			(at 3.750056 -4.750054 270)
			(size 0.2794 1.6002)
			(layers "F.Cu" "F.Mask" "F.Paste")
			(net "P3E_PCH_M2_RX_DP<1>")
		)
		(pad "20" smd rect
			(at -3.800094 -4.500118 270)
			(size 0.2794 1.6002)
			(layers "F.Cu" "F.Mask" "F.Paste")
			(net "NC_M2_0_NC3")
		)
		(pad "21" smd rect
			(at 3.750056 -4.249928 270)
			(size 0.2794 1.6002)
			(layers "F.Cu" "F.Mask" "F.Paste")
			(net "GND")
		)
		(pad "22" smd rect
			(at -3.800094 -3.999992 270)
			(size 0.2794 1.6002)
			(layers "F.Cu" "F.Mask" "F.Paste")
			(net "NC_M2_0_NC4")
		)
		(pad "23" smd rect
			(at 3.750056 -3.750056 270)
			(size 0.2794 1.6002)
			(layers "F.Cu" "F.Mask" "F.Paste")
			(net "P3E_PCH_M2_TX_C_DP<1>")
		)
		(pad "24" smd rect
			(at -3.800094 -3.50012 270)
			(size 0.2794 1.6002)
			(layers "F.Cu" "F.Mask" "F.Paste")
			(net "NC_M2_0_NC5")
		)
		(pad "25" smd rect
			(at 3.750056 -3.24993 270)
			(size 0.2794 1.6002)
			(layers "F.Cu" "F.Mask" "F.Paste")
			(net "P3E_PCH_M2_TX_C_DN<1>")
		)
		(pad "26" smd rect
			(at -3.800094 -2.999994 270)
			(size 0.2794 1.6002)
			(layers "F.Cu" "F.Mask" "F.Paste")
			(net "NC_M2_0_NC6")
		)
		(pad "27" smd rect
			(at 3.750056 -2.750058 270)
			(size 0.2794 1.6002)
			(layers "F.Cu" "F.Mask" "F.Paste")
			(net "GND")
		)
		(pad "28" smd rect
			(at -3.800094 -2.500122 270)
			(size 0.2794 1.6002)
			(layers "F.Cu" "F.Mask" "F.Paste")
			(net "NC_M2_0_NC7")
		)
		(pad "29" smd rect
			(at 3.750056 -2.249932 270)
			(size 0.2794 1.6002)
			(layers "F.Cu" "F.Mask" "F.Paste")
			(net "P3E_PCH_M2_RX_DN<2>")
		)
		(pad "30" smd rect
			(at -3.800094 -1.999996 270)
			(size 0.2794 1.6002)
			(layers "F.Cu" "F.Mask" "F.Paste")
			(net "NC_M2_0_NC8")
		)
		(pad "31" smd rect
			(at 3.750056 -1.75006 270)
			(size 0.2794 1.6002)
			(layers "F.Cu" "F.Mask" "F.Paste")
			(net "P3E_PCH_M2_RX_DP<2>")
		)
		(pad "32" smd rect
			(at -3.800094 -1.500124 270)
			(size 0.2794 1.6002)
			(layers "F.Cu" "F.Mask" "F.Paste")
			(net "NC_M2_0_NC9")
		)
		(pad "33" smd rect
			(at 3.750056 -1.249934 270)
			(size 0.2794 1.6002)
			(layers "F.Cu" "F.Mask" "F.Paste")
			(net "GND")
		)
		(pad "34" smd rect
			(at -3.800094 -0.999998 270)
			(size 0.2794 1.6002)
			(layers "F.Cu" "F.Mask" "F.Paste")
			(net "NC_M2_0_NC10")
		)
		(pad "35" smd rect
			(at 3.750056 -0.750062 270)
			(size 0.2794 1.6002)
			(layers "F.Cu" "F.Mask" "F.Paste")
			(net "P3E_PCH_M2_TX_C_DP<2>")
		)
		(pad "36" smd rect
			(at -3.800094 -0.499872 270)
			(size 0.2794 1.6002)
			(layers "F.Cu" "F.Mask" "F.Paste")
			(net "NC_M2_0_NC11")
		)
		(pad "37" smd rect
			(at 3.750056 -0.249936 270)
			(size 0.2794 1.6002)
			(layers "F.Cu" "F.Mask" "F.Paste")
			(net "P3E_PCH_M2_TX_C_DN<2>")
		)
		(pad "38" smd rect
			(at -3.800094 0 270)
			(size 0.2794 1.6002)
			(layers "F.Cu" "F.Mask" "F.Paste")
			(net "PD_M2_0_DEVSLP")
		)
		(pad "39" smd rect
			(at 3.750056 0.249936 270)
			(size 0.2794 1.6002)
			(layers "F.Cu" "F.Mask" "F.Paste")
			(net "GND")
		)
		(pad "40" smd rect
			(at -3.800094 0.499872 270)
			(size 0.2794 1.6002)
			(layers "F.Cu" "F.Mask" "F.Paste")
			(net "SMB_M2_P0_1V8AUX_SCL")
		)
		(pad "41" smd rect
			(at 3.750056 0.750062 270)
			(size 0.2794 1.6002)
			(layers "F.Cu" "F.Mask" "F.Paste")
			(net "P3E_PCH_M2_RX_DN<3>")
		)
		(pad "42" smd rect
			(at -3.800094 0.999998 270)
			(size 0.2794 1.6002)
			(layers "F.Cu" "F.Mask" "F.Paste")
			(net "SMB_M2_P0_1V8AUX_SDA")
		)
	)
)
